# T6G (Grand Teton) — schematic netlist excerpt (pin names and nets, part order shuffled) for the footprints in the layout excerpt that follows; sources: Cadence DE-HDL packaged netlist, KiCad conversion of 04192023_DAF0TMB3IC0_F0TG_MB_C_brd_V02_OCP.brd

PR245  Q_RES  0 5% CHIP  pkg 0402LF  page 217 : A = VSENSE_PVDDCR_CPU1_P1_DP ; B = VSENSE_PVDDCR_CPU1_P1_VSEN0
R874  Q_RES  4.7K 5% EMPTY  pkg 0201LF  page 342 : A = P1V8_CPU1_RT_1D ; B = GPIO2_RT_CPU1_P2
PR50  Q_RES  49.9 1% CHIP  pkg 0402LF  page 200 : A = VSENSE_VSS_SENSE_B_P0 ; B = GND

(kicad_pcb
	(version 20260206)
	(generator "pcbnew")
	(generator_version "10.0")
	(general
		(thickness 1.6)
		(legacy_teardrops no)
	)
	(paper "A4")
	(title_block
		(title "04192023_DAF0TMB3IC0_F0TG_MB_C_brd_V02_OCP.brd")
		(comment 1 "Grand Teton / footprints 3216-3218 of 8354")
	)
	(layers
		(0 "F.Cu" signal "TOP")
		(4 "In1.Cu" signal "GND")
		(6 "In2.Cu" signal "IN1")
		(8 "In3.Cu" signal "GND1")
		(10 "In4.Cu" signal "IN2")
		(12 "In5.Cu" signal "GND2")
		(14 "In6.Cu" signal "IN3")
		(16 "In7.Cu" signal "GND3")
		(18 "In8.Cu" signal "VCC")
		(20 "In9.Cu" signal "VCC1")
		(22 "In10.Cu" signal "GND4")
		(24 "In11.Cu" signal "IN4")
		(26 "In12.Cu" signal "GND5")
		(28 "In13.Cu" signal "IN5")
		(30 "In14.Cu" signal "GND6")
		(32 "In15.Cu" signal "IN6")
		(34 "In16.Cu" signal "GND7")
		(2 "B.Cu" signal "BOTTOM")
		(9 "F.Adhes" user "F.Adhesive")
		(11 "B.Adhes" user "B.Adhesive")
		(13 "F.Paste" user "Package Geometry/Pastemask Top")
		(15 "B.Paste" user "Package Geometry/Pastemask Bottom")
		(5 "F.SilkS" user "Ref Des/Silkscreen Top")
		(7 "B.SilkS" user "Ref Des/Silkscreen Bottom")
		(1 "F.Mask" user "Board Geometry/Soldermask Top")
		(3 "B.Mask" user "Board Geometry/Soldermask Bottom")
		(17 "Dwgs.User" user "User.Drawings")
		(19 "Cmts.User" user "User.Comments")
		(21 "Eco1.User" user "User.Eco1")
		(23 "Eco2.User" user "User.Eco2")
		(25 "Edge.Cuts" user "Board Geometry/Outline")
		(27 "Margin" user)
		(31 "F.CrtYd" user "Package Geometry/Place Bound Top")
		(29 "B.CrtYd" user "Package Geometry/Place Bound Bottom")
		(35 "F.Fab" user "Ref Des/Assembly Top")
		(33 "B.Fab" user "Ref Des/Assembly Bottom")
	)
	(footprint ""
		(layer "F.Cu")
		(at 27.178 -357.886 90)
		(property "Reference" "PR245"
			(at 0 0 90)
			(layer "F.SilkS")
			(hide yes)
			(effects
				(font
					(size 1.27 1.27)
				)
			)
		)
		(property "Value" ""
			(at 0 0 90)
			(layer "F.Fab")
			(effects
				(font
					(size 1.27 1.27)
				)
			)
		)
		(duplicate_pad_numbers_are_jumpers no)
		(fp_line
			(start 0.7874 -0.4064)
			(end 0.7874 0.4064)
			(stroke
				(width 0.1524)
				(type default)
			)
			(layer "F.SilkS")
		)
		(fp_line
			(start -0.7874 -0.4064)
			(end 0.7874 -0.4064)
			(stroke
				(width 0.1524)
				(type default)
			)
			(layer "F.SilkS")
		)
		(fp_line
			(start 0.7874 0.4064)
			(end -0.7874 0.4064)
			(stroke
				(width 0.1524)
				(type default)
			)
			(layer "F.SilkS")
		)
		(fp_line
			(start -0.7874 0.4064)
			(end -0.7874 -0.4064)
			(stroke
				(width 0.1524)
				(type default)
			)
			(layer "F.SilkS")
		)
		(fp_line
			(start -0.12065 -0.305054)
			(end -0.12065 -0.2794)
			(stroke
				(width 0.1)
				(type default)
			)
			(layer "F.Fab")
		)
		(fp_line
			(start -0.67945 -0.305054)
			(end -0.12065 -0.305054)
			(stroke
				(width 0.1)
				(type default)
			)
			(layer "F.Fab")
		)
		(fp_line
			(start 0.67945 -0.3048)
			(end 0.67945 0.3048)
			(stroke
				(width 0.1)
				(type default)
			)
			(layer "F.Fab")
		)
		(fp_line
			(start 0.12065 -0.3048)
			(end 0.67945 -0.3048)
			(stroke
				(width 0.1)
				(type default)
			)
			(layer "F.Fab")
		)
		(fp_line
			(start 0.12065 -0.2794)
			(end 0.12065 -0.3048)
			(stroke
				(width 0.1)
				(type default)
			)
			(layer "F.Fab")
		)
		(fp_line
			(start -0.12065 -0.2794)
			(end 0.12065 -0.2794)
			(stroke
				(width 0.1)
				(type default)
			)
			(layer "F.Fab")
		)
		(fp_line
			(start 0.120396 0.2794)
			(end -0.12065 0.2794)
			(stroke
				(width 0.1)
				(type default)
			)
			(layer "F.Fab")
		)
		(fp_line
			(start -0.12065 0.2794)
			(end -0.12065 0.3048)
			(stroke
				(width 0.1)
				(type default)
			)
			(layer "F.Fab")
		)
		(fp_line
			(start 0.67945 0.3048)
			(end 0.120396 0.3048)
			(stroke
				(width 0.1)
				(type default)
			)
			(layer "F.Fab")
		)
		(fp_line
			(start 0.120396 0.3048)
			(end 0.120396 0.2794)
			(stroke
				(width 0.1)
				(type default)
			)
			(layer "F.Fab")
		)
		(fp_line
			(start -0.12065 0.3048)
			(end -0.67945 0.3048)
			(stroke
				(width 0.1)
				(type default)
			)
			(layer "F.Fab")
		)
		(fp_line
			(start -0.67945 0.3048)
			(end -0.67945 -0.305054)
			(stroke
				(width 0.1)
				(type default)
			)
			(layer "F.Fab")
		)
		(pad "1" smd circle
			(at -0.40005 0 90)
			(size 0 0)
			(layers "F.Cu" "F.Mask" "F.Paste")
			(net "VSENSE_PVDDCR_CPU1_P1_DP")
		)
		(pad "2" smd circle
			(at 0.40005 0 90)
			(size 0 0)
			(layers "F.Cu" "F.Mask" "F.Paste")
			(net "VSENSE_PVDDCR_CPU1_P1_VSEN0")
		)
	)
	(footprint ""
		(layer "F.Cu")
		(at 269.023084 -333.045562)
		(property "Reference" "PR50"
			(at 0 0 0)
			(layer "F.SilkS")
			(hide yes)
			(effects
				(font
					(size 1.27 1.27)
				)
			)
		)
		(property "Value" ""
			(at 0 0 0)
			(layer "F.Fab")
			(effects
				(font
					(size 1.27 1.27)
				)
			)
		)
		(duplicate_pad_numbers_are_jumpers no)
		(fp_line
			(start -0.7874 -0.4064)
			(end 0.7874 -0.4064)
			(stroke
				(width 0.1524)
				(type default)
			)
			(layer "F.SilkS")
		)
		(fp_line
			(start -0.7874 0.4064)
			(end -0.7874 -0.4064)
			(stroke
				(width 0.1524)
				(type default)
			)
			(layer "F.SilkS")
		)
		(fp_line
			(start 0.7874 -0.4064)
			(end 0.7874 0.4064)
			(stroke
				(width 0.1524)
				(type default)
			)
			(layer "F.SilkS")
		)
		(fp_line
			(start 0.7874 0.4064)
			(end -0.7874 0.4064)
			(stroke
				(width 0.1524)
				(type default)
			)
			(layer "F.SilkS")
		)
		(fp_line
			(start -0.67945 -0.305054)
			(end -0.12065 -0.305054)
			(stroke
				(width 0.1)
				(type default)
			)
			(layer "F.Fab")
		)
		(fp_line
			(start -0.67945 0.3048)
			(end -0.67945 -0.305054)
			(stroke
				(width 0.1)
				(type default)
			)
			(layer "F.Fab")
		)
		(fp_line
			(start -0.12065 -0.305054)
			(end -0.12065 -0.2794)
			(stroke
				(width 0.1)
				(type default)
			)
			(layer "F.Fab")
		)
		(fp_line
			(start -0.12065 -0.2794)
			(end 0.12065 -0.2794)
			(stroke
				(width 0.1)
				(type default)
			)
			(layer "F.Fab")
		)
		(fp_line
			(start -0.12065 0.2794)
			(end -0.12065 0.3048)
			(stroke
				(width 0.1)
				(type default)
			)
			(layer "F.Fab")
		)
		(fp_line
			(start -0.12065 0.3048)
			(end -0.67945 0.3048)
			(stroke
				(width 0.1)
				(type default)
			)
			(layer "F.Fab")
		)
		(fp_line
			(start 0.120396 0.2794)
			(end -0.12065 0.2794)
			(stroke
				(width 0.1)
				(type default)
			)
			(layer "F.Fab")
		)
		(fp_line
			(start 0.120396 0.3048)
			(end 0.120396 0.2794)
			(stroke
				(width 0.1)
				(type default)
			)
			(layer "F.Fab")
		)
		(fp_line
			(start 0.12065 -0.3048)
			(end 0.67945 -0.3048)
			(stroke
				(width 0.1)
				(type default)
			)
			(layer "F.Fab")
		)
		(fp_line
			(start 0.12065 -0.2794)
			(end 0.12065 -0.3048)
			(stroke
				(width 0.1)
				(type default)
			)
			(layer "F.Fab")
		)
		(fp_line
			(start 0.67945 -0.3048)
			(end 0.67945 0.3048)
			(stroke
				(width 0.1)
				(type default)
			)
			(layer "F.Fab")
		)
		(fp_line
			(start 0.67945 0.3048)
			(end 0.120396 0.3048)
			(stroke
				(width 0.1)
				(type default)
			)
			(layer "F.Fab")
		)
		(pad "1" smd circle
			(at -0.40005 0)
			(size 0 0)
			(layers "F.Cu" "F.Mask" "F.Paste")
			(net "VSENSE_VSS_SENSE_B_P0")
		)
		(pad "2" smd circle
			(at 0.40005 0)
			(size 0 0)
			(layers "F.Cu" "F.Mask" "F.Paste")
			(net "GND")
		)
	)
	(footprint ""
		(layer "F.Cu")
		(at 141.623542 -385.48056)
		(property "Reference" "R874"
			(at 0 0 0)
			(layer "F.SilkS")
			(hide yes)
			(effects
				(font
					(size 1.27 1.27)
				)
			)
		)
		(property "Value" ""
			(at 0 0 0)
			(layer "F.Fab")
			(effects
				(font
					(size 1.27 1.27)
				)
			)
		)
		(duplicate_pad_numbers_are_jumpers no)
		(fp_line
			(start -0.32512 -0.175006)
			(end 0.32512 -0.175006)
			(stroke
				(width 0.1)
				(type default)
			)
			(layer "F.Fab")
		)
		(fp_line
			(start -0.32512 0.175006)
			(end -0.32512 -0.175006)
			(stroke
				(width 0.1)
				(type default)
			)
			(layer "F.Fab")
		)
		(fp_line
			(start 0.32512 -0.175006)
			(end 0.32512 0.175006)
			(stroke
				(width 0.1)
				(type default)
			)
			(layer "F.Fab")
		)
		(fp_line
			(start 0.32512 0.175006)
			(end -0.32512 0.175006)
			(stroke
				(width 0.1)
				(type default)
			)
			(layer "F.Fab")
		)
		(pad "1" smd rect
			(at -0.2667 0)
			(size 0.3048 0.381)
			(layers "F.Cu" "F.Mask" "F.Paste")
			(net "P1V8_CPU1_RT_1D")
		)
		(pad "2" smd rect
			(at 0.2667 0 180)
			(size 0.3048 0.381)
			(layers "F.Cu" "F.Mask" "F.Paste")
			(net "GPIO2_RT_CPU1_P2")
		)
	)
)
